(kicad_pcb
	(version 20260206)
	(generator "pcbnew")
	(generator_version "10.0")
	(general
		(thickness 1.6)
		(legacy_teardrops no)
	)
	(paper "A4")
	(title_block
		(title "03242023_DA0F0TMBIJ0_F0T_Motherboard_J_brd_V01_OCP.brd")
		(comment 1 "Grand Teton / footprints 5259-5266 of 6105")
	)
	(layers
		(0 "F.Cu" signal "TOP")
		(4 "In1.Cu" signal "GND")
		(6 "In2.Cu" signal "IN1")
		(8 "In3.Cu" signal "GND1")
		(10 "In4.Cu" signal "IN2")
		(12 "In5.Cu" signal "GND2")
		(14 "In6.Cu" signal "IN3")
		(16 "In7.Cu" signal "GND3")
		(18 "In8.Cu" signal "VCC")
		(20 "In9.Cu" signal "VCC1")
		(22 "In10.Cu" signal "GND4")
		(24 "In11.Cu" signal "IN4")
		(26 "In12.Cu" signal "GND5")
		(28 "In13.Cu" signal "IN5")
		(30 "In14.Cu" signal "GND6")
		(32 "In15.Cu" signal "IN6")
		(34 "In16.Cu" signal "GND7")
		(2 "B.Cu" signal "BOTTOM")
		(9 "F.Adhes" user "F.Adhesive")
		(11 "B.Adhes" user "B.Adhesive")
		(13 "F.Paste" user "Package Geometry/Pastemask Top")
		(15 "B.Paste" user "Package Geometry/Pastemask Bottom")
		(5 "F.SilkS" user "Ref Des/Silkscreen Top")
		(7 "B.SilkS" user "Ref Des/Silkscreen Bottom")
		(1 "F.Mask" user "Board Geometry/Soldermask Top")
		(3 "B.Mask" user "Board Geometry/Soldermask Bottom")
		(17 "Dwgs.User" user "User.Drawings")
		(19 "Cmts.User" user "User.Comments")
		(21 "Eco1.User" user "User.Eco1")
		(23 "Eco2.User" user "User.Eco2")
		(25 "Edge.Cuts" user "Board Geometry/Outline")
		(27 "Margin" user)
		(31 "F.CrtYd" user "Package Geometry/Place Bound Top")
		(29 "B.CrtYd" user "Package Geometry/Place Bound Bottom")
		(35 "F.Fab" user "Ref Des/Assembly Top")
		(33 "B.Fab" user "Ref Des/Assembly Bottom")
	)
	(footprint ""
		(layer "B.Cu")
		(at 179.705 -19.522948 -90)
		(property "Reference" "R4505"
			(at 0 0 90)
			(layer "B.SilkS")
			(hide yes)
			(effects
				(font
					(size 1.27 1.27)
				)
				(justify mirror)
			)
		)
		(property "Value" ""
			(at 0 0 90)
			(layer "B.Fab")
			(effects
				(font
					(size 1.27 1.27)
				)
				(justify mirror)
			)
		)
		(duplicate_pad_numbers_are_jumpers no)
		(fp_line
			(start -0.7874 0.4064)
			(end 0.7874 0.4064)
			(stroke
				(width 0.1524)
				(type default)
			)
			(layer "B.SilkS")
		)
		(fp_line
			(start 0.7874 0.4064)
			(end 0.7874 -0.4064)
			(stroke
				(width 0.1524)
				(type default)
			)
			(layer "B.SilkS")
		)
		(fp_line
			(start -0.7874 -0.4064)
			(end -0.7874 0.4064)
			(stroke
				(width 0.1524)
				(type default)
			)
			(layer "B.SilkS")
		)
		(fp_line
			(start 0.7874 -0.4064)
			(end -0.7874 -0.4064)
			(stroke
				(width 0.1524)
				(type default)
			)
			(layer "B.SilkS")
		)
		(fp_line
			(start -0.67945 0.3048)
			(end -0.120396 0.3048)
			(stroke
				(width 0.1)
				(type default)
			)
			(layer "B.Fab")
		)
		(fp_line
			(start -0.120396 0.3048)
			(end -0.120396 0.2794)
			(stroke
				(width 0.1)
				(type default)
			)
			(layer "B.Fab")
		)
		(fp_line
			(start 0.12065 0.3048)
			(end 0.67945 0.3048)
			(stroke
				(width 0.1)
				(type default)
			)
			(layer "B.Fab")
		)
		(fp_line
			(start 0.67945 0.3048)
			(end 0.67945 -0.305054)
			(stroke
				(width 0.1)
				(type default)
			)
			(layer "B.Fab")
		)
		(fp_line
			(start -0.120396 0.2794)
			(end 0.12065 0.2794)
			(stroke
				(width 0.1)
				(type default)
			)
			(layer "B.Fab")
		)
		(fp_line
			(start 0.12065 0.2794)
			(end 0.12065 0.3048)
			(stroke
				(width 0.1)
				(type default)
			)
			(layer "B.Fab")
		)
		(fp_line
			(start -0.12065 -0.2794)
			(end -0.12065 -0.3048)
			(stroke
				(width 0.1)
				(type default)
			)
			(layer "B.Fab")
		)
		(fp_line
			(start 0.12065 -0.2794)
			(end -0.12065 -0.2794)
			(stroke
				(width 0.1)
				(type default)
			)
			(layer "B.Fab")
		)
		(fp_line
			(start -0.67945 -0.3048)
			(end -0.67945 0.3048)
			(stroke
				(width 0.1)
				(type default)
			)
			(layer "B.Fab")
		)
		(fp_line
			(start -0.12065 -0.3048)
			(end -0.67945 -0.3048)
			(stroke
				(width 0.1)
				(type default)
			)
			(layer "B.Fab")
		)
		(fp_line
			(start 0.12065 -0.305054)
			(end 0.12065 -0.2794)
			(stroke
				(width 0.1)
				(type default)
			)
			(layer "B.Fab")
		)
		(fp_line
			(start 0.67945 -0.305054)
			(end 0.12065 -0.305054)
			(stroke
				(width 0.1)
				(type default)
			)
			(layer "B.Fab")
		)
		(pad "1" smd circle
			(at 0.40005 0 90)
			(size 0 0)
			(layers "B.Cu" "B.Mask" "B.Paste")
			(net "SMB_SML1_PMBUS_3V3AUX_PCH_SCL")
		)
		(pad "2" smd circle
			(at -0.40005 0 90)
			(size 0 0)
			(layers "B.Cu" "B.Mask" "B.Paste")
			(net "SMB_SML1_PMBUS_3V3AUX_PCH_SCL_1")
		)
	)
	(footprint ""
		(layer "B.Cu")
		(at 107.457494 -238.04372 -90)
		(property "Reference" "C1387"
			(at 0 0 90)
			(layer "B.SilkS")
			(hide yes)
			(effects
				(font
					(size 1.27 1.27)
				)
				(justify mirror)
			)
		)
		(property "Value" ""
			(at 0 0 90)
			(layer "B.Fab")
			(effects
				(font
					(size 1.27 1.27)
				)
				(justify mirror)
			)
		)
		(duplicate_pad_numbers_are_jumpers no)
		(fp_line
			(start -1.524 0.762)
			(end 1.524 0.762)
			(stroke
				(width 0.1524)
				(type default)
			)
			(layer "B.SilkS")
		)
		(fp_line
			(start 1.524 0.762)
			(end 1.524 -0.762)
			(stroke
				(width 0.1524)
				(type default)
			)
			(layer "B.SilkS")
		)
		(fp_line
			(start -1.524 -0.762)
			(end -1.524 0.762)
			(stroke
				(width 0.1524)
				(type default)
			)
			(layer "B.SilkS")
		)
		(fp_line
			(start 1.524 -0.762)
			(end -1.524 -0.762)
			(stroke
				(width 0.1524)
				(type default)
			)
			(layer "B.SilkS")
		)
		(fp_line
			(start -1.1049 0.724916)
			(end -1.1049 -0.724916)
			(stroke
				(width 0.1)
				(type default)
			)
			(layer "B.Fab")
		)
		(fp_line
			(start 1.1049 0.724916)
			(end -1.1049 0.724916)
			(stroke
				(width 0.1)
				(type default)
			)
			(layer "B.Fab")
		)
		(fp_line
			(start -1.1049 -0.724916)
			(end 1.1049 -0.724916)
			(stroke
				(width 0.1)
				(type default)
			)
			(layer "B.Fab")
		)
		(fp_line
			(start 1.1049 -0.724916)
			(end 1.1049 0.724916)
			(stroke
				(width 0.1)
				(type default)
			)
			(layer "B.Fab")
		)
		(pad "1" smd rect
			(at 0.889 0 270)
			(size 1.016 1.27)
			(layers "B.Cu" "B.Mask" "B.Paste")
			(net "PVNN_MAIN_CPU1")
		)
		(pad "2" smd rect
			(at -0.889 0 270)
			(size 1.016 1.27)
			(layers "B.Cu" "B.Mask" "B.Paste")
			(net "GND")
		)
	)
	(footprint ""
		(layer "B.Cu")
		(at 144.399 -9.362948 -90)
		(property "Reference" "R1383"
			(at 0 0 90)
			(layer "B.SilkS")
			(hide yes)
			(effects
				(font
					(size 1.27 1.27)
				)
				(justify mirror)
			)
		)
		(property "Value" ""
			(at 0 0 90)
			(layer "B.Fab")
			(effects
				(font
					(size 1.27 1.27)
				)
				(justify mirror)
			)
		)
		(duplicate_pad_numbers_are_jumpers no)
		(fp_line
			(start -0.7874 0.4064)
			(end 0.7874 0.4064)
			(stroke
				(width 0.1524)
				(type default)
			)
			(layer "B.SilkS")
		)
		(fp_line
			(start 0.7874 0.4064)
			(end 0.7874 -0.4064)
			(stroke
				(width 0.1524)
				(type default)
			)
			(layer "B.SilkS")
		)
		(fp_line
			(start -0.7874 -0.4064)
			(end -0.7874 0.4064)
			(stroke
				(width 0.1524)
				(type default)
			)
			(layer "B.SilkS")
		)
		(fp_line
			(start 0.7874 -0.4064)
			(end -0.7874 -0.4064)
			(stroke
				(width 0.1524)
				(type default)
			)
			(layer "B.SilkS")
		)
		(fp_line
			(start -0.67945 0.3048)
			(end -0.120396 0.3048)
			(stroke
				(width 0.1)
				(type default)
			)
			(layer "B.Fab")
		)
		(fp_line
			(start -0.120396 0.3048)
			(end -0.120396 0.2794)
			(stroke
				(width 0.1)
				(type default)
			)
			(layer "B.Fab")
		)
		(fp_line
			(start 0.12065 0.3048)
			(end 0.67945 0.3048)
			(stroke
				(width 0.1)
				(type default)
			)
			(layer "B.Fab")
		)
		(fp_line
			(start 0.67945 0.3048)
			(end 0.67945 -0.305054)
			(stroke
				(width 0.1)
				(type default)
			)
			(layer "B.Fab")
		)
		(fp_line
			(start -0.120396 0.2794)
			(end 0.12065 0.2794)
			(stroke
				(width 0.1)
				(type default)
			)
			(layer "B.Fab")
		)
		(fp_line
			(start 0.12065 0.2794)
			(end 0.12065 0.3048)
			(stroke
				(width 0.1)
				(type default)
			)
			(layer "B.Fab")
		)
		(fp_line
			(start -0.12065 -0.2794)
			(end -0.12065 -0.3048)
			(stroke
				(width 0.1)
				(type default)
			)
			(layer "B.Fab")
		)
		(fp_line
			(start 0.12065 -0.2794)
			(end -0.12065 -0.2794)
			(stroke
				(width 0.1)
				(type default)
			)
			(layer "B.Fab")
		)
		(fp_line
			(start -0.67945 -0.3048)
			(end -0.67945 0.3048)
			(stroke
				(width 0.1)
				(type default)
			)
			(layer "B.Fab")
		)
		(fp_line
			(start -0.12065 -0.3048)
			(end -0.67945 -0.3048)
			(stroke
				(width 0.1)
				(type default)
			)
			(layer "B.Fab")
		)
		(fp_line
			(start 0.12065 -0.305054)
			(end 0.12065 -0.2794)
			(stroke
				(width 0.1)
				(type default)
			)
			(layer "B.Fab")
		)
		(fp_line
			(start 0.67945 -0.305054)
			(end 0.12065 -0.305054)
			(stroke
				(width 0.1)
				(type default)
			)
			(layer "B.Fab")
		)
		(pad "1" smd circle
			(at 0.40005 0 90)
			(size 0 0)
			(layers "B.Cu" "B.Mask" "B.Paste")
			(net "P3V3_AUX")
		)
		(pad "2" smd circle
			(at -0.40005 0 90)
			(size 0 0)
			(layers "B.Cu" "B.Mask" "B.Paste")
			(net "JTAG_BMC_DBP_PREQ_N")
		)
	)
	(footprint ""
		(layer "B.Cu")
		(at 361.691174 -362.698792 180)
		(property "Reference" "PR176"
			(at 0 0 0)
			(layer "B.SilkS")
			(hide yes)
			(effects
				(font
					(size 1.27 1.27)
				)
				(justify mirror)
			)
		)
		(property "Value" ""
			(at 0 0 0)
			(layer "B.Fab")
			(effects
				(font
					(size 1.27 1.27)
				)
				(justify mirror)
			)
		)
		(duplicate_pad_numbers_are_jumpers no)
		(fp_line
			(start 0.7874 0.4064)
			(end 0.7874 -0.4064)
			(stroke
				(width 0.1524)
				(type default)
			)
			(layer "B.SilkS")
		)
		(fp_line
			(start 0.7874 -0.4064)
			(end -0.7874 -0.4064)
			(stroke
				(width 0.1524)
				(type default)
			)
			(layer "B.SilkS")
		)
		(fp_line
			(start -0.7874 0.4064)
			(end 0.7874 0.4064)
			(stroke
				(width 0.1524)
				(type default)
			)
			(layer "B.SilkS")
		)
		(fp_line
			(start -0.7874 -0.4064)
			(end -0.7874 0.4064)
			(stroke
				(width 0.1524)
				(type default)
			)
			(layer "B.SilkS")
		)
		(fp_line
			(start 0.67945 0.3048)
			(end 0.67945 -0.305054)
			(stroke
				(width 0.1)
				(type default)
			)
			(layer "B.Fab")
		)
		(fp_line
			(start 0.67945 -0.305054)
			(end 0.12065 -0.305054)
			(stroke
				(width 0.1)
				(type default)
			)
			(layer "B.Fab")
		)
		(fp_line
			(start 0.12065 0.3048)
			(end 0.67945 0.3048)
			(stroke
				(width 0.1)
				(type default)
			)
			(layer "B.Fab")
		)
		(fp_line
			(start 0.12065 0.2794)
			(end 0.12065 0.3048)
			(stroke
				(width 0.1)
				(type default)
			)
			(layer "B.Fab")
		)
		(fp_line
			(start 0.12065 -0.2794)
			(end -0.12065 -0.2794)
			(stroke
				(width 0.1)
				(type default)
			)
			(layer "B.Fab")
		)
		(fp_line
			(start 0.12065 -0.305054)
			(end 0.12065 -0.2794)
			(stroke
				(width 0.1)
				(type default)
			)
			(layer "B.Fab")
		)
		(fp_line
			(start -0.120396 0.3048)
			(end -0.120396 0.2794)
			(stroke
				(width 0.1)
				(type default)
			)
			(layer "B.Fab")
		)
		(fp_line
			(start -0.120396 0.2794)
			(end 0.12065 0.2794)
			(stroke
				(width 0.1)
				(type default)
			)
			(layer "B.Fab")
		)
		(fp_line
			(start -0.12065 -0.2794)
			(end -0.12065 -0.3048)
			(stroke
				(width 0.1)
				(type default)
			)
			(layer "B.Fab")
		)
		(fp_line
			(start -0.12065 -0.3048)
			(end -0.67945 -0.3048)
			(stroke
				(width 0.1)
				(type default)
			)
			(layer "B.Fab")
		)
		(fp_line
			(start -0.67945 0.3048)
			(end -0.120396 0.3048)
			(stroke
				(width 0.1)
				(type default)
			)
			(layer "B.Fab")
		)
		(fp_line
			(start -0.67945 -0.3048)
			(end -0.67945 0.3048)
			(stroke
				(width 0.1)
				(type default)
			)
			(layer "B.Fab")
		)
		(pad "1" smd circle
			(at 0.40005 0)
			(size 0 0)
			(layers "B.Cu" "B.Mask" "B.Paste")
			(net "PVCCIN_CPU0_VCC")
		)
		(pad "2" smd circle
			(at -0.40005 0)
			(size 0 0)
			(layers "B.Cu" "B.Mask" "B.Paste")
			(net "P3V3_AUX")
		)
	)
	(footprint ""
		(layer "B.Cu")
		(at 309.55742 -33.22574 180)
		(property "Reference" "R4766"
			(at 0 0 0)
			(layer "B.SilkS")
			(hide yes)
			(effects
				(font
					(size 1.27 1.27)
				)
				(justify mirror)
			)
		)
		(property "Value" ""
			(at 0 0 0)
			(layer "B.Fab")
			(effects
				(font
					(size 1.27 1.27)
				)
				(justify mirror)
			)
		)
		(duplicate_pad_numbers_are_jumpers no)
		(fp_line
			(start 0.7874 0.4064)
			(end 0.7874 -0.4064)
			(stroke
				(width 0.1524)
				(type default)
			)
			(layer "B.SilkS")
		)
		(fp_line
			(start 0.7874 -0.4064)
			(end -0.7874 -0.4064)
			(stroke
				(width 0.1524)
				(type default)
			)
			(layer "B.SilkS")
		)
		(fp_line
			(start -0.7874 0.4064)
			(end 0.7874 0.4064)
			(stroke
				(width 0.1524)
				(type default)
			)
			(layer "B.SilkS")
		)
		(fp_line
			(start -0.7874 -0.4064)
			(end -0.7874 0.4064)
			(stroke
				(width 0.1524)
				(type default)
			)
			(layer "B.SilkS")
		)
		(fp_line
			(start 0.67945 0.3048)
			(end 0.67945 -0.305054)
			(stroke
				(width 0.1)
				(type default)
			)
			(layer "B.Fab")
		)
		(fp_line
			(start 0.67945 -0.305054)
			(end 0.12065 -0.305054)
			(stroke
				(width 0.1)
				(type default)
			)
			(layer "B.Fab")
		)
		(fp_line
			(start 0.12065 0.3048)
			(end 0.67945 0.3048)
			(stroke
				(width 0.1)
				(type default)
			)
			(layer "B.Fab")
		)
		(fp_line
			(start 0.12065 0.2794)
			(end 0.12065 0.3048)
			(stroke
				(width 0.1)
				(type default)
			)
			(layer "B.Fab")
		)
		(fp_line
			(start 0.12065 -0.2794)
			(end -0.12065 -0.2794)
			(stroke
				(width 0.1)
				(type default)
			)
			(layer "B.Fab")
		)
		(fp_line
			(start 0.12065 -0.305054)
			(end 0.12065 -0.2794)
			(stroke
				(width 0.1)
				(type default)
			)
			(layer "B.Fab")
		)
		(fp_line
			(start -0.120396 0.3048)
			(end -0.120396 0.2794)
			(stroke
				(width 0.1)
				(type default)
			)
			(layer "B.Fab")
		)
		(fp_line
			(start -0.120396 0.2794)
			(end 0.12065 0.2794)
			(stroke
				(width 0.1)
				(type default)
			)
			(layer "B.Fab")
		)
		(fp_line
			(start -0.12065 -0.2794)
			(end -0.12065 -0.3048)
			(stroke
				(width 0.1)
				(type default)
			)
			(layer "B.Fab")
		)
		(fp_line
			(start -0.12065 -0.3048)
			(end -0.67945 -0.3048)
			(stroke
				(width 0.1)
				(type default)
			)
			(layer "B.Fab")
		)
		(fp_line
			(start -0.67945 0.3048)
			(end -0.120396 0.3048)
			(stroke
				(width 0.1)
				(type default)
			)
			(layer "B.Fab")
		)
		(fp_line
			(start -0.67945 -0.3048)
			(end -0.67945 0.3048)
			(stroke
				(width 0.1)
				(type default)
			)
			(layer "B.Fab")
		)
		(pad "1" smd circle
			(at 0.40005 0)
			(size 0 0)
			(layers "B.Cu" "B.Mask" "B.Paste")
			(net "E1S_0_CLK_OE_N")
		)
		(pad "2" smd circle
			(at -0.40005 0)
			(size 0 0)
			(layers "B.Cu" "B.Mask" "B.Paste")
			(net "E1S_0_CLKREQ_N")
		)
	)
	(footprint ""
		(layer "B.Cu")
		(at 184.969404 -353.573842 90)
		(property "Reference" "PC1201_P1_3"
			(at 0 0 90)
			(layer "B.SilkS")
			(hide yes)
			(effects
				(font
					(size 1.27 1.27)
				)
				(justify mirror)
			)
		)
		(property "Value" ""
			(at 0 0 90)
			(layer "B.Fab")
			(effects
				(font
					(size 1.27 1.27)
				)
				(justify mirror)
			)
		)
		(duplicate_pad_numbers_are_jumpers no)
		(fp_line
			(start 1.524 -0.762)
			(end -1.524 -0.762)
			(stroke
				(width 0.1524)
				(type default)
			)
			(layer "B.SilkS")
		)
		(fp_line
			(start -1.524 -0.762)
			(end -1.524 0.762)
			(stroke
				(width 0.1524)
				(type default)
			)
			(layer "B.SilkS")
		)
		(fp_line
			(start 1.524 0.762)
			(end 1.524 -0.762)
			(stroke
				(width 0.1524)
				(type default)
			)
			(layer "B.SilkS")
		)
		(fp_line
			(start -1.524 0.762)
			(end 1.524 0.762)
			(stroke
				(width 0.1524)
				(type default)
			)
			(layer "B.SilkS")
		)
		(fp_line
			(start 1.1049 -0.724916)
			(end 1.1049 0.724916)
			(stroke
				(width 0.1)
				(type default)
			)
			(layer "B.Fab")
		)
		(fp_line
			(start -1.1049 -0.724916)
			(end 1.1049 -0.724916)
			(stroke
				(width 0.1)
				(type default)
			)
			(layer "B.Fab")
		)
		(fp_line
			(start 1.1049 0.724916)
			(end -1.1049 0.724916)
			(stroke
				(width 0.1)
				(type default)
			)
			(layer "B.Fab")
		)
		(fp_line
			(start -1.1049 0.724916)
			(end -1.1049 -0.724916)
			(stroke
				(width 0.1)
				(type default)
			)
			(layer "B.Fab")
		)
		(pad "1" smd rect
			(at 0.889 0 90)
			(size 1.016 1.27)
			(layers "B.Cu" "B.Mask" "B.Paste")
			(net "SW_P12V_PVCCFA_EHV_FIVRA_CPU1_R")
		)
		(pad "2" smd rect
			(at -0.889 0 90)
			(size 1.016 1.27)
			(layers "B.Cu" "B.Mask" "B.Paste")
			(net "GND")
		)
	)
	(footprint ""
		(layer "B.Cu")
		(at 342.251792 -64.088264 90)
		(property "Reference" "C164"
			(at 0 0 90)
			(layer "B.SilkS")
			(hide yes)
			(effects
				(font
					(size 1.27 1.27)
				)
				(justify mirror)
			)
		)
		(property "Value" ""
			(at 0 0 90)
			(layer "B.Fab")
			(effects
				(font
					(size 1.27 1.27)
				)
				(justify mirror)
			)
		)
		(duplicate_pad_numbers_are_jumpers no)
		(fp_line
			(start 0.299974 -0.150114)
			(end -0.299974 -0.150114)
			(stroke
				(width 0.1)
				(type default)
			)
			(layer "B.Fab")
		)
		(fp_line
			(start -0.299974 -0.150114)
			(end -0.299974 0.150114)
			(stroke
				(width 0.1)
				(type default)
			)
			(layer "B.Fab")
		)
		(fp_line
			(start 0.299974 0.150114)
			(end 0.299974 -0.150114)
			(stroke
				(width 0.1)
				(type default)
			)
			(layer "B.Fab")
		)
		(fp_line
			(start -0.299974 0.150114)
			(end 0.299974 0.150114)
			(stroke
				(width 0.1)
				(type default)
			)
			(layer "B.Fab")
		)
		(pad "1" smd rect
			(at 0.2667 0 270)
			(size 0.3048 0.381)
			(layers "B.Cu" "B.Mask" "B.Paste")
			(net "DMI_CPU0_PCH_RX_C_DP<3>")
		)
		(pad "2" smd rect
			(at -0.2667 0 270)
			(size 0.3048 0.381)
			(layers "B.Cu" "B.Mask" "B.Paste")
			(net "DMI_CPU0_PCH_RX_DP<3>")
		)
	)
	(footprint ""
		(layer "B.Cu")
		(at 302.150526 -49.06772 180)
		(property "Reference" "C1247"
			(at 0 0 0)
			(layer "B.SilkS")
			(hide yes)
			(effects
				(font
					(size 1.27 1.27)
				)
				(justify mirror)
			)
		)
		(property "Value" ""
			(at 0 0 0)
			(layer "B.Fab")
			(effects
				(font
					(size 1.27 1.27)
				)
				(justify mirror)
			)
		)
		(duplicate_pad_numbers_are_jumpers no)
		(fp_line
			(start 1.524 0.762)
			(end 1.524 -0.762)
			(stroke
				(width 0.1524)
				(type default)
			)
			(layer "B.SilkS")
		)
		(fp_line
			(start 1.524 -0.762)
			(end -1.524 -0.762)
			(stroke
				(width 0.1524)
				(type default)
			)
			(layer "B.SilkS")
		)
		(fp_line
			(start -1.524 0.762)
			(end 1.524 0.762)
			(stroke
				(width 0.1524)
				(type default)
			)
			(layer "B.SilkS")
		)
		(fp_line
			(start -1.524 -0.762)
			(end -1.524 0.762)
			(stroke
				(width 0.1524)
				(type default)
			)
			(layer "B.SilkS")
		)
		(fp_line
			(start 1.1049 0.724916)
			(end -1.1049 0.724916)
			(stroke
				(width 0.1)
				(type default)
			)
			(layer "B.Fab")
		)
		(fp_line
			(start 1.1049 -0.724916)
			(end 1.1049 0.724916)
			(stroke
				(width 0.1)
				(type default)
			)
			(layer "B.Fab")
		)
		(fp_line
			(start -1.1049 0.724916)
			(end -1.1049 -0.724916)
			(stroke
				(width 0.1)
				(type default)
			)
			(layer "B.Fab")
		)
		(fp_line
			(start -1.1049 -0.724916)
			(end 1.1049 -0.724916)
			(stroke
				(width 0.1)
				(type default)
			)
			(layer "B.Fab")
		)
		(pad "1" smd rect
			(at 0.889 0 180)
			(size 1.016 1.27)
			(layers "B.Cu" "B.Mask" "B.Paste")
			(net "P1V05_PCH_AUX")
		)
		(pad "2" smd rect
			(at -0.889 0 180)
			(size 1.016 1.27)
			(layers "B.Cu" "B.Mask" "B.Paste")
			(net "GND")
		)
	)
)
